(kicad_pcb
	(version 20211014)
	(generator pcbnew)
	(general
    (thickness 1.6)
  )
	(paper "A4")
	(title_block
    (title "SA800U (Snapdragon 845) Baseboard")
    (date "2023-10-19")
    (rev "1.0.3")
    (company "Antmicro Ltd.")
    (comment 1 "www.antmicro.com")
		(comment 9 "footprints 521-535 of 589")
	)
	(layers
    (0 "F.Cu" signal)
    (1 "In1.Cu" power)
    (2 "In2.Cu" signal)
    (3 "In3.Cu" signal)
    (4 "In4.Cu" power)
    (31 "B.Cu" signal)
    (32 "B.Adhes" user "B.Adhesive")
    (33 "F.Adhes" user "F.Adhesive")
    (34 "B.Paste" user)
    (35 "F.Paste" user)
    (36 "B.SilkS" user "B.Silkscreen")
    (37 "F.SilkS" user "F.Silkscreen")
    (38 "B.Mask" user)
    (39 "F.Mask" user)
    (40 "Dwgs.User" user "User.Drawings")
    (41 "Cmts.User" user "User.Comments")
    (42 "Eco1.User" user "User.Eco1")
    (43 "Eco2.User" user "User.Eco2")
    (44 "Edge.Cuts" user)
    (45 "Margin" user)
    (46 "B.CrtYd" user "B.Courtyard")
    (47 "F.CrtYd" user "F.Courtyard")
    (48 "B.Fab" user)
    (49 "F.Fab" user)
  )
	(footprint "sa800u-baseboard-hw-footprints:TP_SMD_0.75mm" (layer "B.Cu")
    (tedit 5E4A9375)
    (at 82.4 120.4)
    (property "Author" "Antmicro")
    (property "License" "Apache-2.0")
    (property "MPN" "")
    (property "Manufacturer" "")
    (property "Sheetfile" "psu.kicad_sch")
    (property "Sheetname" "PSU")
    (attr smd)
    (fp_text reference "TP59" (at 0.42 -3.01 90) (layer "B.SilkS")
      (effects (font (size 0.7 0.7) (thickness 0.15)) (justify left bottom mirror))
    )
    (fp_text value "TP_0.75mm_SMD" (at 0 -1.2 180) (layer "B.Fab")
      (effects (font (size 0.7 0.7) (thickness 0.15)) (justify left bottom mirror))
    )
    (fp_text user "License: Apache-2.0" (at -0.4 -5.101 180) (layer "B.Fab") hide
      (effects (font (size 0.7 0.7) (thickness 0.15)) (justify left bottom mirror))
    )
    (fp_text user "${REFERENCE}" (at -0.4 -2.7 180) (layer "B.Fab") hide
      (effects (font (size 0.7 0.7) (thickness 0.15)) (justify left bottom mirror))
    )
    (fp_text user "Author: Antmicro" (at -0.4 -3.901 180) (layer "B.Fab") hide
      (effects (font (size 0.7 0.7) (thickness 0.15)) (justify left bottom mirror))
    )
    (pad "1" smd circle (at 0 0) (size 0.75 0.75) (layers "B.Cu" "B.Mask")
      (net 405 "Net-(R123-Pad2)") (pinfunction "1") (pintype "passive"))
  )
	(footprint "sa800u-baseboard-hw-footprints:TP_SMD_0.75mm" (layer "B.Cu")
    (tedit 5E4A9375)
    (at 76 122.3492)
    (property "Author" "Antmicro")
    (property "License" "Apache-2.0")
    (property "MPN" "")
    (property "Manufacturer" "")
    (property "Sheetfile" "psu.kicad_sch")
    (property "Sheetname" "PSU")
    (attr smd)
    (fp_text reference "TP60" (at -0.46 -0.4992 270) (layer "B.SilkS")
      (effects (font (size 0.7 0.7) (thickness 0.15)) (justify left bottom mirror))
    )
    (fp_text value "TP_0.75mm_SMD" (at 0 -1.2 180) (layer "B.Fab")
      (effects (font (size 0.7 0.7) (thickness 0.15)) (justify left bottom mirror))
    )
    (fp_text user "License: Apache-2.0" (at -0.4 -5.101 180) (layer "B.Fab") hide
      (effects (font (size 0.7 0.7) (thickness 0.15)) (justify left bottom mirror))
    )
    (fp_text user "Author: Antmicro" (at -0.4 -3.901 180) (layer "B.Fab") hide
      (effects (font (size 0.7 0.7) (thickness 0.15)) (justify left bottom mirror))
    )
    (fp_text user "${REFERENCE}" (at -0.4 -2.7 180) (layer "B.Fab") hide
      (effects (font (size 0.7 0.7) (thickness 0.15)) (justify left bottom mirror))
    )
    (pad "1" smd circle (at 0 0) (size 0.75 0.75) (layers "B.Cu" "B.Mask")
      (net 406 "Net-(R125-Pad2)") (pinfunction "1") (pintype "passive"))
  )
	(footprint "sa800u-baseboard-hw-footprints:TP_SMD_0.75mm" (layer "B.Cu")
    (tedit 5E4A9375)
    (at 87 117.2)
    (property "Author" "Antmicro")
    (property "License" "Apache-2.0")
    (property "MPN" "")
    (property "Manufacturer" "")
    (property "Sheetfile" "psu.kicad_sch")
    (property "Sheetname" "PSU")
    (attr smd)
    (fp_text reference "TP67" (at 0.43 -3.09 270) (layer "B.SilkS")
      (effects (font (size 0.7 0.7) (thickness 0.15)) (justify left bottom mirror))
    )
    (fp_text value "TP_0.75mm_SMD" (at 0 -1.2 180) (layer "B.Fab")
      (effects (font (size 0.7 0.7) (thickness 0.15)) (justify left bottom mirror))
    )
    (fp_text user "${REFERENCE}" (at -0.4 -2.7 180) (layer "B.Fab") hide
      (effects (font (size 0.7 0.7) (thickness 0.15)) (justify left bottom mirror))
    )
    (fp_text user "Author: Antmicro" (at -0.4 -3.901 180) (layer "B.Fab") hide
      (effects (font (size 0.7 0.7) (thickness 0.15)) (justify left bottom mirror))
    )
    (fp_text user "License: Apache-2.0" (at -0.4 -5.101 180) (layer "B.Fab") hide
      (effects (font (size 0.7 0.7) (thickness 0.15)) (justify left bottom mirror))
    )
    (pad "1" smd circle (at 0 0) (size 0.75 0.75) (layers "B.Cu" "B.Mask")
      (net 156 "/PSU/BYPASS_EN") (pinfunction "1") (pintype "passive"))
  )
	(footprint "sa800u-baseboard-hw-footprints:TP_SMD_0.75mm" (layer "B.Cu")
    (tedit 5E4A9375)
    (at 88.4 117.2)
    (property "Author" "Antmicro")
    (property "License" "Apache-2.0")
    (property "MPN" "")
    (property "Manufacturer" "")
    (property "Sheetfile" "psu.kicad_sch")
    (property "Sheetname" "PSU")
    (attr smd)
    (fp_text reference "TP69" (at 0.19 -3.05 270) (layer "B.SilkS")
      (effects (font (size 0.7 0.7) (thickness 0.15)) (justify left bottom mirror))
    )
    (fp_text value "TP_0.75mm_SMD" (at 0 -1.2 180) (layer "B.Fab")
      (effects (font (size 0.7 0.7) (thickness 0.15)) (justify left bottom mirror))
    )
    (fp_text user "License: Apache-2.0" (at -0.4 -5.101 180) (layer "B.Fab") hide
      (effects (font (size 0.7 0.7) (thickness 0.15)) (justify left bottom mirror))
    )
    (fp_text user "${REFERENCE}" (at -0.4 -2.7 180) (layer "B.Fab") hide
      (effects (font (size 0.7 0.7) (thickness 0.15)) (justify left bottom mirror))
    )
    (fp_text user "Author: Antmicro" (at -0.4 -3.901 180) (layer "B.Fab") hide
      (effects (font (size 0.7 0.7) (thickness 0.15)) (justify left bottom mirror))
    )
    (pad "1" smd circle (at 0 0) (size 0.75 0.75) (layers "B.Cu" "B.Mask")
      (net 164 "/PSU/5V_DC_DC_ENABLE") (pinfunction "1") (pintype "passive"))
  )
	(footprint "sa800u-baseboard-hw-footprints:TP_SMD_0.75mm" (layer "B.Cu")
    (tedit 5E4A9375)
    (at 87.4 98.2)
    (property "Author" "Antmicro")
    (property "License" "Apache-2.0")
    (property "MPN" "")
    (property "Manufacturer" "")
    (property "Sheetfile" "psu.kicad_sch")
    (property "Sheetname" "PSU")
    (attr smd)
    (fp_text reference "TP64" (at 1.24 -0.49 180) (layer "B.SilkS")
      (effects (font (size 0.7 0.7) (thickness 0.15)) (justify left bottom mirror))
    )
    (fp_text value "TP_0.75mm_SMD" (at 0 -1.2 180) (layer "B.Fab")
      (effects (font (size 0.7 0.7) (thickness 0.15)) (justify left bottom mirror))
    )
    (fp_text user "Author: Antmicro" (at -0.4 -3.901 180) (layer "B.Fab") hide
      (effects (font (size 0.7 0.7) (thickness 0.15)) (justify left bottom mirror))
    )
    (fp_text user "License: Apache-2.0" (at -0.4 -5.101 180) (layer "B.Fab") hide
      (effects (font (size 0.7 0.7) (thickness 0.15)) (justify left bottom mirror))
    )
    (fp_text user "${REFERENCE}" (at -0.4 -2.7 180) (layer "B.Fab") hide
      (effects (font (size 0.7 0.7) (thickness 0.15)) (justify left bottom mirror))
    )
    (pad "1" smd circle (at 0 0) (size 0.75 0.75) (layers "B.Cu" "B.Mask")
      (net 409 "Net-(R131-Pad2)") (pinfunction "1") (pintype "passive"))
  )
	(footprint "sa800u-baseboard-hw-footprints:TP_SMD_0.75mm" (layer "B.Cu")
    (tedit 5E4A9375)
    (at 78.4 110.2)
    (property "Author" "Antmicro")
    (property "License" "Apache-2.0")
    (property "MPN" "")
    (property "Manufacturer" "")
    (property "Sheetfile" "psu.kicad_sch")
    (property "Sheetname" "PSU")
    (attr smd)
    (fp_text reference "TP65" (at 1.13 -0.4 180) (layer "B.SilkS")
      (effects (font (size 0.7 0.7) (thickness 0.15)) (justify left bottom mirror))
    )
    (fp_text value "TP_0.75mm_SMD" (at 0 -1.2 180) (layer "B.Fab")
      (effects (font (size 0.7 0.7) (thickness 0.15)) (justify left bottom mirror))
    )
    (fp_text user "Author: Antmicro" (at -0.4 -3.901 180) (layer "B.Fab") hide
      (effects (font (size 0.7 0.7) (thickness 0.15)) (justify left bottom mirror))
    )
    (fp_text user "${REFERENCE}" (at -0.4 -2.7 180) (layer "B.Fab") hide
      (effects (font (size 0.7 0.7) (thickness 0.15)) (justify left bottom mirror))
    )
    (fp_text user "License: Apache-2.0" (at -0.4 -5.101 180) (layer "B.Fab") hide
      (effects (font (size 0.7 0.7) (thickness 0.15)) (justify left bottom mirror))
    )
    (pad "1" smd circle (at 0 0) (size 0.75 0.75) (layers "B.Cu" "B.Mask")
      (net 407 "Net-(R127-Pad2)") (pinfunction "1") (pintype "passive"))
  )
	(footprint "sa800u-baseboard-hw-footprints:TP_SMD_0.75mm" (layer "B.Cu")
    (tedit 5E4A9375)
    (at 123.4 126.2)
    (property "Author" "Antmicro")
    (property "License" "Apache-2.0")
    (property "MPN" "")
    (property "Manufacturer" "")
    (property "Sheetfile" "psu.kicad_sch")
    (property "Sheetname" "PSU")
    (attr smd)
    (fp_text reference "TP66" (at -0.32 0.38 180) (layer "B.SilkS")
      (effects (font (size 0.7 0.7) (thickness 0.15)) (justify left bottom mirror))
    )
    (fp_text value "TP_0.75mm_SMD" (at 0 -1.2 180) (layer "B.Fab")
      (effects (font (size 0.7 0.7) (thickness 0.15)) (justify left bottom mirror))
    )
    (fp_text user "License: Apache-2.0" (at -0.4 -5.101 180) (layer "B.Fab") hide
      (effects (font (size 0.7 0.7) (thickness 0.15)) (justify left bottom mirror))
    )
    (fp_text user "Author: Antmicro" (at -0.4 -3.901 180) (layer "B.Fab") hide
      (effects (font (size 0.7 0.7) (thickness 0.15)) (justify left bottom mirror))
    )
    (fp_text user "${REFERENCE}" (at -0.4 -2.7 180) (layer "B.Fab") hide
      (effects (font (size 0.7 0.7) (thickness 0.15)) (justify left bottom mirror))
    )
    (pad "1" smd circle (at 0 0) (size 0.75 0.75) (layers "B.Cu" "B.Mask")
      (net 408 "Net-(R128-Pad2)") (pinfunction "1") (pintype "passive"))
  )
	(footprint "sa800u-baseboard-hw-footprints:TP_SMD_0.75mm" (layer "B.Cu")
    (tedit 5E4A9375)
    (at 94.9 129.5 90)
    (property "Author" "Antmicro")
    (property "License" "Apache-2.0")
    (property "MPN" "")
    (property "Manufacturer" "")
    (property "Sheetfile" "usb-pd.kicad_sch")
    (property "Sheetname" "USB-PD")
    (attr smd)
    (fp_text reference "TP89" (at -0.37 -0.36) (layer "B.SilkS")
      (effects (font (size 0.7 0.7) (thickness 0.15)) (justify left bottom mirror))
    )
    (fp_text value "TP_0.75mm_SMD" (at 0 -1.2 270) (layer "B.Fab")
      (effects (font (size 0.7 0.7) (thickness 0.15)) (justify left bottom mirror))
    )
    (fp_text user "License: Apache-2.0" (at -0.4 -5.101 270) (layer "B.Fab") hide
      (effects (font (size 0.7 0.7) (thickness 0.15)) (justify left bottom mirror))
    )
    (fp_text user "Author: Antmicro" (at -0.4 -3.901 270) (layer "B.Fab") hide
      (effects (font (size 0.7 0.7) (thickness 0.15)) (justify left bottom mirror))
    )
    (fp_text user "${REFERENCE}" (at -0.4 -2.7 270) (layer "B.Fab") hide
      (effects (font (size 0.7 0.7) (thickness 0.15)) (justify left bottom mirror))
    )
    (pad "1" smd circle (at 0 0 90) (size 0.75 0.75) (layers "B.Cu" "B.Mask")
      (net 332 "/USB-PD/ALERT") (pinfunction "1") (pintype "passive"))
  )
	(footprint "sa800u-baseboard-hw-footprints:TP_SMD_0.75mm" (layer "B.Cu")
    (tedit 5E4A9375)
    (at 95 127)
    (property "Author" "Antmicro")
    (property "License" "Apache-2.0")
    (property "MPN" "")
    (property "Manufacturer" "")
    (property "Sheetfile" "usb-pd.kicad_sch")
    (property "Sheetname" "USB-PD")
    (attr smd)
    (fp_text reference "TP91" (at -0.31 0.37 180) (layer "B.SilkS")
      (effects (font (size 0.7 0.7) (thickness 0.15)) (justify left bottom mirror))
    )
    (fp_text value "TP_0.75mm_SMD" (at 0 -1.2 180) (layer "B.Fab")
      (effects (font (size 0.7 0.7) (thickness 0.15)) (justify left bottom mirror))
    )
    (fp_text user "${REFERENCE}" (at -0.4 -2.7 180) (layer "B.Fab") hide
      (effects (font (size 0.7 0.7) (thickness 0.15)) (justify left bottom mirror))
    )
    (fp_text user "Author: Antmicro" (at -0.4 -3.901 180) (layer "B.Fab") hide
      (effects (font (size 0.7 0.7) (thickness 0.15)) (justify left bottom mirror))
    )
    (fp_text user "License: Apache-2.0" (at -0.4 -5.101 180) (layer "B.Fab") hide
      (effects (font (size 0.7 0.7) (thickness 0.15)) (justify left bottom mirror))
    )
    (pad "1" smd circle (at 0 0) (size 0.75 0.75) (layers "B.Cu" "B.Mask")
      (net 333 "/USB-PD/AB_SIDE") (pinfunction "1") (pintype "passive"))
  )
	(footprint "sa800u-baseboard-hw-footprints:TP_SMD_0.75mm" (layer "B.Cu")
    (tedit 5E4A9375)
    (at 94.95 125.8 90)
    (property "Author" "Antmicro")
    (property "License" "Apache-2.0")
    (property "MPN" "")
    (property "Manufacturer" "")
    (property "Sheetfile" "usb-pd.kicad_sch")
    (property "Sheetname" "USB-PD")
    (attr smd)
    (fp_text reference "TP95" (at -0.27 -0.3) (layer "B.SilkS")
      (effects (font (size 0.7 0.7) (thickness 0.15)) (justify left bottom mirror))
    )
    (fp_text value "TP_0.75mm_SMD" (at 0 -1.2 270) (layer "B.Fab")
      (effects (font (size 0.7 0.7) (thickness 0.15)) (justify left bottom mirror))
    )
    (fp_text user "License: Apache-2.0" (at -0.4 -5.101 270) (layer "B.Fab") hide
      (effects (font (size 0.7 0.7) (thickness 0.15)) (justify left bottom mirror))
    )
    (fp_text user "${REFERENCE}" (at -0.4 -2.7 270) (layer "B.Fab") hide
      (effects (font (size 0.7 0.7) (thickness 0.15)) (justify left bottom mirror))
    )
    (fp_text user "Author: Antmicro" (at -0.4 -3.901 270) (layer "B.Fab") hide
      (effects (font (size 0.7 0.7) (thickness 0.15)) (justify left bottom mirror))
    )
    (pad "1" smd circle (at 0 0 90) (size 0.75 0.75) (layers "B.Cu" "B.Mask")
      (net 334 "/USB-PD/GPIO") (pinfunction "1") (pintype "passive"))
  )
	(footprint "sa800u-baseboard-hw-footprints:TP_SMD_0.75mm" (layer "B.Cu")
    (tedit 5E4A9375)
    (at 111.6 107)
    (property "Author" "Antmicro")
    (property "License" "Apache-2.0")
    (property "MPN" "")
    (property "Manufacturer" "")
    (property "Sheetfile" "other-interfaces.kicad_sch")
    (property "Sheetname" "Other Interfaces")
    (attr smd)
    (fp_text reference "TP44" (at -0.37 0.38 180) (layer "B.SilkS")
      (effects (font (size 0.7 0.7) (thickness 0.15)) (justify left bottom mirror))
    )
    (fp_text value "TP_0.75mm_SMD" (at 0 -1.2 180) (layer "B.Fab")
      (effects (font (size 0.7 0.7) (thickness 0.15)) (justify left bottom mirror))
    )
    (fp_text user "License: Apache-2.0" (at -0.4 -5.101 180) (layer "B.Fab") hide
      (effects (font (size 0.7 0.7) (thickness 0.15)) (justify left bottom mirror))
    )
    (fp_text user "Author: Antmicro" (at -0.4 -3.901 180) (layer "B.Fab") hide
      (effects (font (size 0.7 0.7) (thickness 0.15)) (justify left bottom mirror))
    )
    (fp_text user "${REFERENCE}" (at -0.4 -2.7 180) (layer "B.Fab") hide
      (effects (font (size 0.7 0.7) (thickness 0.15)) (justify left bottom mirror))
    )
    (pad "1" smd circle (at 0 0) (size 0.75 0.75) (layers "B.Cu" "B.Mask")
      (net 151 "I2C10_SDA") (pinfunction "1") (pintype "passive"))
  )
	(footprint "sa800u-baseboard-hw-footprints:TP_SMD_0.75mm" (layer "B.Cu")
    (tedit 5E4A9375)
    (at 111.6 108.2)
    (property "Author" "Antmicro")
    (property "License" "Apache-2.0")
    (property "MPN" "")
    (property "Manufacturer" "")
    (property "Sheetfile" "other-interfaces.kicad_sch")
    (property "Sheetname" "Other Interfaces")
    (attr smd)
    (fp_text reference "TP45" (at -0.37 0.38 180) (layer "B.SilkS")
      (effects (font (size 0.7 0.7) (thickness 0.15)) (justify left bottom mirror))
    )
    (fp_text value "TP_0.75mm_SMD" (at 0 -1.2 180) (layer "B.Fab")
      (effects (font (size 0.7 0.7) (thickness 0.15)) (justify left bottom mirror))
    )
    (fp_text user "${REFERENCE}" (at -0.4 -2.7 180) (layer "B.Fab") hide
      (effects (font (size 0.7 0.7) (thickness 0.15)) (justify left bottom mirror))
    )
    (fp_text user "Author: Antmicro" (at -0.4 -3.901 180) (layer "B.Fab") hide
      (effects (font (size 0.7 0.7) (thickness 0.15)) (justify left bottom mirror))
    )
    (fp_text user "License: Apache-2.0" (at -0.4 -5.101 180) (layer "B.Fab") hide
      (effects (font (size 0.7 0.7) (thickness 0.15)) (justify left bottom mirror))
    )
    (pad "1" smd circle (at 0 0) (size 0.75 0.75) (layers "B.Cu" "B.Mask")
      (net 150 "I2C10_SCL") (pinfunction "1") (pintype "passive"))
  )
	(footprint "sa800u-baseboard-hw-footprints:TP_SMD_0.75mm" (layer "B.Cu")
    (tedit 5E4A9375)
    (at 115.9 108.2)
    (property "Author" "Antmicro")
    (property "License" "Apache-2.0")
    (property "MPN" "")
    (property "Manufacturer" "")
    (property "Sheetfile" "other-interfaces.kicad_sch")
    (property "Sheetname" "Other Interfaces")
    (attr smd)
    (fp_text reference "TP46" (at -0.37 0.38 180) (layer "B.SilkS")
      (effects (font (size 0.7 0.7) (thickness 0.15)) (justify left bottom mirror))
    )
    (fp_text value "TP_0.75mm_SMD" (at 0 -1.2 180) (layer "B.Fab")
      (effects (font (size 0.7 0.7) (thickness 0.15)) (justify left bottom mirror))
    )
    (fp_text user "${REFERENCE}" (at -0.4 -2.7 180) (layer "B.Fab") hide
      (effects (font (size 0.7 0.7) (thickness 0.15)) (justify left bottom mirror))
    )
    (fp_text user "Author: Antmicro" (at -0.4 -3.901 180) (layer "B.Fab") hide
      (effects (font (size 0.7 0.7) (thickness 0.15)) (justify left bottom mirror))
    )
    (fp_text user "License: Apache-2.0" (at -0.4 -5.101 180) (layer "B.Fab") hide
      (effects (font (size 0.7 0.7) (thickness 0.15)) (justify left bottom mirror))
    )
    (pad "1" smd circle (at 0 0) (size 0.75 0.75) (layers "B.Cu" "B.Mask")
      (net 337 "/Other Interfaces/I2C10_SCL_3V3") (pinfunction "1") (pintype "passive"))
  )
	(footprint "sa800u-baseboard-hw-footprints:TP_SMD_0.75mm" (layer "B.Cu")
    (tedit 5E4A9375)
    (at 115.9 107)
    (property "Author" "Antmicro")
    (property "License" "Apache-2.0")
    (property "MPN" "")
    (property "Manufacturer" "")
    (property "Sheetfile" "other-interfaces.kicad_sch")
    (property "Sheetname" "Other Interfaces")
    (attr smd)
    (fp_text reference "TP47" (at -0.37 0.38 180) (layer "B.SilkS")
      (effects (font (size 0.7 0.7) (thickness 0.15)) (justify left bottom mirror))
    )
    (fp_text value "TP_0.75mm_SMD" (at 0 -1.2 180) (layer "B.Fab")
      (effects (font (size 0.7 0.7) (thickness 0.15)) (justify left bottom mirror))
    )
    (fp_text user "License: Apache-2.0" (at -0.4 -5.101 180) (layer "B.Fab") hide
      (effects (font (size 0.7 0.7) (thickness 0.15)) (justify left bottom mirror))
    )
    (fp_text user "${REFERENCE}" (at -0.4 -2.7 180) (layer "B.Fab") hide
      (effects (font (size 0.7 0.7) (thickness 0.15)) (justify left bottom mirror))
    )
    (fp_text user "Author: Antmicro" (at -0.4 -3.901 180) (layer "B.Fab") hide
      (effects (font (size 0.7 0.7) (thickness 0.15)) (justify left bottom mirror))
    )
    (pad "1" smd circle (at 0 0) (size 0.75 0.75) (layers "B.Cu" "B.Mask")
      (net 338 "/Other Interfaces/I2C10_SDA_3V3") (pinfunction "1") (pintype "passive"))
  )
	(footprint "sa800u-baseboard-hw-footprints:TP_SMD_0.75mm" (layer "B.Cu")
    (tedit 5E4A9375)
    (at 95 128.2)
    (property "Author" "Antmicro")
    (property "License" "Apache-2.0")
    (property "MPN" "")
    (property "Manufacturer" "")
    (property "Sheetfile" "usb-pd.kicad_sch")
    (property "Sheetname" "USB-PD")
    (attr smd)
    (fp_text reference "TP96" (at -0.43 0.4 180) (layer "B.SilkS")
      (effects (font (size 0.7 0.7) (thickness 0.15)) (justify left bottom mirror))
    )
    (fp_text value "TP_0.75mm_SMD" (at 0 -1.2 180) (layer "B.Fab")
      (effects (font (size 0.7 0.7) (thickness 0.15)) (justify left bottom mirror))
    )
    (fp_text user "Author: Antmicro" (at -0.4 -3.901 180) (layer "B.Fab") hide
      (effects (font (size 0.7 0.7) (thickness 0.15)) (justify left bottom mirror))
    )
    (fp_text user "License: Apache-2.0" (at -0.4 -5.101 180) (layer "B.Fab") hide
      (effects (font (size 0.7 0.7) (thickness 0.15)) (justify left bottom mirror))
    )
    (fp_text user "${REFERENCE}" (at -0.4 -2.7 180) (layer "B.Fab") hide
      (effects (font (size 0.7 0.7) (thickness 0.15)) (justify left bottom mirror))
    )
    (pad "1" smd circle (at 0 0) (size 0.75 0.75) (layers "B.Cu" "B.Mask")
      (net 335 "/USB-PD/ATTACH") (pinfunction "1") (pintype "passive"))
  )
)
